FILE_TYPE = CONNECTIVITY;
{Allegro Design Entry HDL 17.4-2019 S026 (4007227) 1/17/2022}
"PAGE_NUMBER" = 434;
0"NC";
END.
